FILE_TYPE = CONNECTIVITY;
{Allegro Design Entry HDL 16.6-p007 (v16-6-112F) 10/10/2012}
"PAGE_NUMBER" = 156;
0"NC";
1"P3V3_STBY\g";
2"P3V3_STBY\g";
3"P3V3_STBY\g";
4"GND\g";
5"P3V3_STBY\g";
6"P3V3_STBY\g";
7"GND\g";
8"GND\g";
9"P3V3_STBY\g";
10"GND\g";
11"GND\g";
12"GND\g";
13"P3V3_STBY\g";
14"P3V3_STBY\g";
15"GND\g";
16"GND\g";
17"P3V3_STBY\g";
18"GND\g";
19"GND\g";
20"RST_BMC_SYSRST_BTN_OUT_B_N";
21"FM_CPU_BMC_INIT";
22"SMB_HOST_STBY_LVC3_SDA";
23"IRQ_BMC_PCH_NMI_STBY_N";
24"RST_BMC_SYSRST_BTN_OUT_N";
25"FM_PCH_PWRBTN_N";
26"FM_BMC_PWRBTN_OUT_N";
27"IRQ_BMC_PCH_NMI_STBY_R_N";
28"RST_BMC_SYSRST_BTN_OUT_B_R_N";
29"FM_PCH_PWRBTN_R_N";
30"RST_PCH_SYSRST_BTN_OUT_N";
31"FM_PCH_PWRBTN_OUT_N";
32"FM_ADR_SMI_GPIO_N";
33"FM_MEM_THERM_EVENT_LVT3_N";
34"FM_CPU0_SM_WP";
35"FM_CPU1_SM_WP";
36"SMB_LAN_STBY_LVC3_SDA";
37"SMB_LAN_STBY_LVC3_SCL";
38"SMB_PIROM_CPU1_SDA";
39"SMB_PIROM_CPU0_SDA";
40"SMB_PIROM_CPU1_SCL";
41"SMB_PIROM_CPU0_SCL";
42"H_CPU0_BMCINIT";
43"H_CPU1_BMCINIT";
44"PD_PIROM_CPU0_ADDR0";
45"PD_PIROM_CPU0_ADDR1";
46"PD_PIROM_CPU0_ADDR2";
47"PU_PIROM_CPU1_ADDR0";
48"PD_PIROM_CPU1_ADDR1";
49"PD_PIROM_CPU1_ADDR2";
50"SMB_SMLINK0_STBY_LVC3_SCL";
51"SMB_SMLINK0_STBY_LVC3_SDA";
52"SMB_HOST_STBY_LVC3_SCL";
%"RES"
"2","(-4150,4450)","0","mstr_discrete","I206";
;
CDS_SEC"1"
MATERIAL"CHIP"
PACK_TYPE"0402"
TOLERANCE"1%"
PART_NUMBER"G21796-072"
WATTAGE"1/16W"
VALUE"4.75K"
LOCATION"R2T34"
CDS_LOCATION"R2T34"
CDS_LIB"mstr_discrete"
BOM_COST"SM_CONTROLLER"
SEC_TYPE"0402"
SEC"1"
ROOM"BMC_MISC";
"A"
$PN"1"1;
"B"
$PN"2"26;
%"RES"
"2","(-3825,4450)","0","mstr_discrete","I207";
;
CDS_SEC"1"
VALUE"4.75K"
WATTAGE"1/16W"
PART_NUMBER"G21796-072"
PACK_TYPE"0402"
LOCATION"R2T35"
TOLERANCE"1%"
MATERIAL"CHIP"
CDS_LOCATION"R2T35"
CDS_LIB"mstr_discrete"
SEC_TYPE"0402"
BOM_COST"SM_CONTROLLER"
SEC"1"
ROOM"BMC_MISC";
"A"
$PN"1"1;
"B"
$PN"2"24;
%"P3V3_STBY"
"1","(-4150,4850)","0","mstr_symbols","I208";
;
VOLTAGE"3.3V"
CDS_LIB"mstr_symbols"
SIZE"1B"
BODY_TYPE"PLUMBING"
HDL_POWER"P3V3_STBY";
"G\NAC"1;
%"P3V3_STBY"
"1","(-2400,4850)","0","mstr_symbols","I209";
;
VOLTAGE"3.3V"
CDS_LIB"mstr_symbols"
SIZE"1B"
BODY_TYPE"PLUMBING"
HDL_POWER"P3V3_STBY";
"G\NAC"2;
%"RES"
"2","(-2275,4425)","0","mstr_discrete","I210";
;
CDS_SEC"1"
WATTAGE"1/16W"
PART_NUMBER"G21796-016"
TOLERANCE"1%"
VALUE"10.0K"
LOCATION"R2T22"
PACK_TYPE"0402"
MATERIAL"CHIP"
CDS_LIB"mstr_discrete"
CDS_LOCATION"R2T22"
ROOM"BMC_MISC"
SEC"1"
SEC_TYPE"0402"
BOM_COST"SM_CONTROLLER";
"A"
$PN"1"2;
"B"
$PN"2"28;
%"RES"
"2","(-2550,4450)","0","mstr_discrete","I211";
;
CDS_SEC"1"
LOCATION"R8F26"
PACK_TYPE"0402"
WATTAGE"1/16W"
TOLERANCE"1%"
MATERIAL"CHIP"
PART_NUMBER"G21796-016"
VALUE"10.0K"
CDS_LOCATION"R8F26"
CDS_LIB"mstr_discrete"
ROOM"BMC_MISC"
SEC"1"
SEC_TYPE"0402"
BOM_COST"SM_CONTROLLER";
"A"
$PN"1"2;
"B"
$PN"2"29;
%"RES"
"1","(-6575,2775)","0","mstr_discrete","I214";
;
CDS_SEC"1"
PART_NUMBER"G21796-074"
MATERIAL"CHIP"
TOLERANCE"1%"
VALUE"33.2"
LOCATION"R8E24"
WATTAGE"1/16W"
PACK_TYPE"0402"
CDS_LIB"mstr_discrete"
SEC_TYPE"0402"
BOM_COST"SM_CONTROLLER"
SEC"1"
CDS_LOCATION"R8E24"
ROOM"BMC_MISC";
"B"
$PN"2"27;
"A"
$PN"1"23;
%"RES"
"2","(-6825,3025)","0","mstr_discrete","I215";
;
CDS_SEC"1"
PACK_TYPE"0402"
PART_NUMBER"G21796-072"
LOCATION"R8E22"
VALUE"4.75K"
WATTAGE"1/16W"
MATERIAL"CHIP"
TOLERANCE"1%"
CDS_LIB"mstr_discrete"
SEC_TYPE"0402"
BOM_COST"SM_CONTROLLER"
SEC"1"
CDS_LOCATION"R8E22"
ROOM"BMC_MISC";
"A"
$PN"1"3;
"B"
$PN"2"23;
%"P3V3_STBY"
"1","(-6825,3275)","0","mstr_symbols","I216";
;
CDS_LIB"mstr_symbols"
VOLTAGE"3.3V"
SIZE"1B"
BODY_TYPE"PLUMBING"
HDL_POWER"P3V3_STBY";
"G\NAC"3;
%"GND"
"1","(-7275,4300)","0","mstr_symbols","I257";
;
HDL_POWER"GND"
BODY_TYPE"PLUMBING"
CDS_LIB"mstr_symbols"
SIZE"1B"
VOLTAGE"0.0V";
"A\NAC"4;
%"RES"
"2","(-3825,3250)","0","mstr_discrete","I265";
;
CDS_SEC"1"
PART_NUMBER"G21796-072"
PACK_TYPE"0402"
WATTAGE"1/16W"
TOLERANCE"1%"
VALUE"4.75K"
MATERIAL"CHIP"
LOCATION"R2U2"
CDS_LIB"mstr_discrete"
BOM_COST"SM_CONTROLLER"
SEC_TYPE"0402"
SEC"1"
CDS_LOCATION"R2U2"
ROOM"BMC_MISC";
"A"
$PN"1"5;
"B"
$PN"2"30;
%"P3V3_STBY"
"1","(-4150,3650)","0","mstr_symbols","I266";
;
VOLTAGE"3.3V"
SIZE"1B"
CDS_LIB"mstr_symbols"
BODY_TYPE"PLUMBING"
HDL_POWER"P3V3_STBY";
"G\NAC"5;
%"RES"
"2","(-4150,3250)","0","mstr_discrete","I267";
;
CDS_SEC"1"
VALUE"4.75K"
PART_NUMBER"G21796-072"
PACK_TYPE"0402"
MATERIAL"CHIP"
WATTAGE"1/16W"
TOLERANCE"1%"
LOCATION"R8G2"
CDS_LIB"mstr_discrete"
CDS_LOCATION"R8G2"
SEC_TYPE"0402"
BOM_COST"SM_CONTROLLER"
SEC"1"
ROOM"BMC_MISC";
"A"
$PN"1"5;
"B"
$PN"2"31;
%"P3V3_STBY"
"1","(-3200,3700)","0","mstr_symbols","I272";
;
VOLTAGE"3.3V"
CDS_LIB"mstr_symbols"
SIZE"1B"
BODY_TYPE"PLUMBING"
HDL_POWER"P3V3_STBY";
"G\NAC"6;
%"CAP_A"
"1","(-3200,3450)","0","dev_discrete","I273";
;
PACK_TYPE"0402V"
VOLTAGE"16V"
VALUE"0.1UF"
LOCATION"C2T35"
PART_NUMBER"A36096-030"
TOLERANCE"10%"
MATERIAL"X7R"
SEC_TYPE"0402V"
BOM_COST"SM_CONTROLLER"
ROOM"BMC_MISC"
SEC"1"
CDS_SEC"1"
CDS_LOCATION"C2T35"
CDS_LIB"dev_discrete";
"B"
$PN"2"7;
"A"
$PN"1"6;
%"GND"
"1","(-3200,3250)","0","mstr_symbols","I274";
;
HDL_POWER"GND"
BODY_TYPE"PLUMBING"
VOLTAGE"0.0V"
SIZE"1B"
CDS_LIB"mstr_symbols";
"A\NAC"7;
%"CAP_A"
"1","(-3200,4600)","0","dev_discrete","I275";
;
VALUE"0.1UF"
LOCATION"C8F16"
MATERIAL"X7R"
VOLTAGE"16V"
TOLERANCE"10%"
PART_NUMBER"A36096-030"
PACK_TYPE"0402V"
CDS_LOCATION"C8F16"
CDS_LIB"dev_discrete"
CDS_SEC"1"
SEC"1"
ROOM"BMC_MISC"
BOM_COST"SM_CONTROLLER"
SEC_TYPE"0402V";
"B"
$PN"2"8;
"A"
$PN"1"9;
%"GND"
"1","(-3200,4400)","0","mstr_symbols","I276";
;
VOLTAGE"0.0V"
CDS_LIB"mstr_symbols"
SIZE"1B"
BODY_TYPE"PLUMBING"
HDL_POWER"GND";
"A\NAC"8;
%"P3V3_STBY"
"1","(-3200,4850)","0","mstr_symbols","I277";
;
CDS_LIB"mstr_symbols"
SIZE"1B"
VOLTAGE"3.3V"
BODY_TYPE"PLUMBING"
HDL_POWER"P3V3_STBY";
"G\NAC"9;
%"RES"
"1","(-6600,2350)","0","mstr_discrete","I279";
;
CDS_SEC"1"
MATERIAL"EMPTY"
WATTAGE"1/16W"
VALUE"0.0"
LOCATION"R8E11"
PART_NUMBER"G21497-005"
PACK_TYPE"0402"
TOLERANCE"5%"
CDS_LIB"mstr_discrete"
CDS_LOCATION"R8E11"
SEC_TYPE"0402"
SEC"1"
ROOM"BMC_MISC"
BOM_COST"SM_CONTROLLER";
"B"
$PN"2"32;
"A"
$PN"1"33;
%"CONN3_C95678002"
"1","(-7575,3700)","0","mstr_conn","I281";
;
CDS_SEC"1"
CONFIG"021.60545.0103"
LOCATION"J9B2"
PART_NUMBER"C95678-002"
MATERIAL"CONN"
CDS_LIB"mstr_conn"
SEC_TYPE"PIP"
SEC"1"
CDS_LOCATION"J9B2"
ROOM"DEBUG"
PACK_TYPE"PIP"
BOM_COST"DEBUG";
"IO1 \B"
$PN"1"51;
"IO2 \B"
$PN"2"10;
"IO3 \B"
$PN"3"50;
%"GND"
"1","(-7275,3550)","0","mstr_symbols","I282";
;
HDL_POWER"GND"
BODY_TYPE"PLUMBING"
VOLTAGE"0.0V"
SIZE"1B"
CDS_LIB"mstr_symbols";
"A\NAC"10;
%"CONN3_C95678002"
"1","(-7600,4475)","0","mstr_conn","I285";
;
CDS_SEC"1"
LOCATION"J8C1"
MATERIAL"CONN"
PART_NUMBER"C95678-002"
CONFIG"021.60545.0103"
CDS_LIB"mstr_conn"
SEC_TYPE"PIP"
BOM_COST"DEBUG"
SEC"1"
CDS_LOCATION"J8C1"
ROOM"DEBUG"
PACK_TYPE"PIP";
"IO1 \B"
$PN"1"22;
"IO2 \B"
$PN"2"4;
"IO3 \B"
$PN"3"52;
%"RES"
"1","(-1700,4200)","0","mstr_discrete","I288";
;
CDS_SEC"1"
VALUE"49.9"
TOLERANCE"1%"
PACK_TYPE"0402"
MATERIAL"CHIP"
WATTAGE"1/16W"
PART_NUMBER"G21796-047"
LOCATION"R2T18"
CDS_LIB"mstr_discrete"
CDS_LOCATION"R2T18"
SEC"1"
SEC_TYPE"0402"
BOM_COST"SM_CONTROLLER"
ROOM"BMC_MISC";
"B"
$PN"2"20;
"A"
$PN"1"28;
%"RES"
"1","(-1700,4100)","6","mstr_discrete","I289";
;
CDS_SEC"1"
MATERIAL"CHIP"
PACK_TYPE"0402"
TOLERANCE"1%"
LOCATION"R2T28"
WATTAGE"1/16W"
PART_NUMBER"G21796-074"
VALUE"33.2"
CDS_LIB"mstr_discrete"
SEC_TYPE"0402"
SEC"1"
CDS_LOCATION"R2T28"
BOM_COST"SM_CONTROLLER"
ROOM"BMC_MISC";
"B"
$PN"2"25;
"A"
$PN"1"29;
%"RES"
"1","(-2900,1825)","0","mstr_discrete","I299";
;
CDS_SEC"1"
CDS_LOCATION"R6D16"
LOCATION"R6D16"
VALUE"0.0"
TOLERANCE"5%"
PART_NUMBER"G21497-005"
WATTAGE"1/16W"
PACK_TYPE"0402"
MATERIAL"EMPTY"
CDS_LIB"mstr_discrete"
ROOM"BMC_MISC"
SEC_TYPE"0402"
SEC"1"
BOM_COST"SM_CONTROLLER";
"B"
$PN"2"42;
"A"
$PN"1"21;
%"RES"
"1","(-2900,1550)","0","mstr_discrete","I300";
;
CDS_SEC"1"
CDS_LOCATION"R3D31"
VALUE"0.0"
WATTAGE"1/16W"
TOLERANCE"5%"
PACK_TYPE"0402"
PART_NUMBER"G21497-005"
LOCATION"R3D31"
MATERIAL"EMPTY"
SEC"1"
CDS_LIB"mstr_discrete"
SEC_TYPE"0402"
ROOM"BMC_MISC"
BOM_COST"SM_CONTROLLER";
"B"
$PN"2"43;
"A"
$PN"1"21;
%"RES"
"1","(-4000,975)","0","mstr_discrete","I302";
;
CDS_SEC"1"
CDS_LOCATION"R6N14"
LOCATION"R6N14"
VALUE"1.00K"
TOLERANCE"1%"
MATERIAL"CHIP"
WATTAGE"1/16W"
PART_NUMBER"G21796-026"
PACK_TYPE"0402"
CDS_LIB"mstr_discrete"
ROOM"CPU0"
SEC"1"
SEC_TYPE"0402";
"B"
$PN"2"44;
"A"
$PN"1"11;
%"RES"
"1","(-4000,775)","0","mstr_discrete","I303";
;
CDS_SEC"1"
CDS_LOCATION"R6N13"
PACK_TYPE"0402"
LOCATION"R6N13"
PART_NUMBER"G21796-026"
VALUE"1.00K"
TOLERANCE"1%"
WATTAGE"1/16W"
MATERIAL"CHIP"
CDS_LIB"mstr_discrete"
ROOM"CPU0"
SEC"1"
SEC_TYPE"0402";
"B"
$PN"2"45;
"A"
$PN"1"11;
%"RES"
"1","(-4000,575)","0","mstr_discrete","I304";
;
CDS_SEC"1"
CDS_LOCATION"R6N15"
TOLERANCE"1%"
WATTAGE"1/16W"
MATERIAL"CHIP"
PACK_TYPE"0402"
PART_NUMBER"G21796-026"
VALUE"1.00K"
LOCATION"R6N15"
ROOM"CPU0"
CDS_LIB"mstr_discrete"
SEC_TYPE"0402"
SEC"1";
"B"
$PN"2"46;
"A"
$PN"1"11;
%"GND"
"1","(-4275,425)","0","mstr_symbols","I306";
;
CDS_LIB"mstr_symbols"
SIZE"1B"
VOLTAGE"0.0V"
BODY_TYPE"PLUMBING"
HDL_POWER"GND";
"A\NAC"11;
%"GND"
"1","(-2175,425)","0","mstr_symbols","I311";
;
CDS_LIB"mstr_symbols"
SIZE"1B"
VOLTAGE"0.0V"
BODY_TYPE"PLUMBING"
HDL_POWER"GND";
"A\NAC"12;
%"RES"
"1","(-1900,575)","0","mstr_discrete","I312";
;
CDS_SEC"1"
CDS_LOCATION"R1C32"
LOCATION"R1C32"
PART_NUMBER"G21796-026"
PACK_TYPE"0402"
WATTAGE"1/16W"
MATERIAL"CHIP"
TOLERANCE"1%"
VALUE"1.00K"
ROOM"CPU1"
CDS_LIB"mstr_discrete"
SEC"1"
SEC_TYPE"0402";
"B"
$PN"2"49;
"A"
$PN"1"12;
%"RES"
"1","(-1900,775)","0","mstr_discrete","I313";
;
CDS_SEC"1"
CDS_LOCATION"R1C33"
MATERIAL"CHIP"
PACK_TYPE"0402"
PART_NUMBER"G21796-026"
WATTAGE"1/16W"
LOCATION"R1C33"
VALUE"1.00K"
TOLERANCE"1%"
ROOM"CPU1"
SEC"1"
SEC_TYPE"0402"
CDS_LIB"mstr_discrete";
"B"
$PN"2"48;
"A"
$PN"1"12;
%"P3V3_STBY"
"1","(-2175,1100)","0","mstr_symbols","I318";
;
SIZE"1B"
CDS_LIB"mstr_symbols"
VOLTAGE"3.3V"
BODY_TYPE"PLUMBING"
HDL_POWER"P3V3_STBY";
"G\NAC"13;
%"RES"
"1","(-1900,975)","0","mstr_discrete","I320";
;
CDS_SEC"1"
CDS_LOCATION"R1C34"
LOCATION"R1C34"
VALUE"10.0K"
TOLERANCE"1%"
WATTAGE"1/16W"
PART_NUMBER"G21796-016"
PACK_TYPE"0402"
MATERIAL"CHIP"
CDS_LIB"mstr_discrete"
SEC_TYPE"0402"
SEC"1"
ROOM"CPU1";
"B"
$PN"2"47;
"A"
$PN"1"13;
%"RES"
"1","(-6425,850)","0","mstr_discrete","I321";
;
CDS_SEC"1"
CDS_LOCATION"R9M21"
PACK_TYPE"0402"
MATERIAL"CHIP"
WATTAGE"1/16W"
TOLERANCE"5%"
PART_NUMBER"G21497-005"
VALUE"0.0"
LOCATION"R9M21"
CDS_LIB"mstr_discrete"
ROOM"CPU1"
SEC_TYPE"0402"
SEC"1";
"B"
$PN"2"38;
"A"
$PN"1"36;
%"RES"
"1","(-6425,700)","0","mstr_discrete","I322";
;
CDS_SEC"1"
CDS_LOCATION"R4A8"
WATTAGE"1/16W"
PART_NUMBER"G21497-005"
PACK_TYPE"0402"
VALUE"0.0"
MATERIAL"CHIP"
TOLERANCE"5%"
LOCATION"R4A8"
CDS_LIB"mstr_discrete"
SEC_TYPE"0402"
SEC"1"
ROOM"CPU0";
"B"
$PN"2"39;
"A"
$PN"1"36;
%"RES"
"1","(-6425,550)","0","mstr_discrete","I323";
;
CDS_SEC"1"
CDS_LOCATION"R9M20"
PACK_TYPE"0402"
PART_NUMBER"G21497-005"
WATTAGE"1/16W"
MATERIAL"CHIP"
TOLERANCE"5%"
VALUE"0.0"
LOCATION"R9M20"
CDS_LIB"mstr_discrete"
SEC_TYPE"0402"
SEC"1"
ROOM"CPU1";
"B"
$PN"2"40;
"A"
$PN"1"37;
%"RES"
"1","(-6425,400)","0","mstr_discrete","I324";
;
CDS_SEC"1"
CDS_LOCATION"R4A9"
WATTAGE"1/16W"
PACK_TYPE"0402"
MATERIAL"CHIP"
PART_NUMBER"G21497-005"
VALUE"0.0"
TOLERANCE"5%"
LOCATION"R4A9"
CDS_LIB"mstr_discrete"
SEC"1"
SEC_TYPE"0402"
ROOM"CPU0";
"B"
$PN"2"41;
"A"
$PN"1"37;
%"RES"
"2","(-7650,1700)","0","mstr_discrete","I331";
;
CDS_SEC"1"
CDS_LOCATION"R3P54"
PACK_TYPE"0402"
PART_NUMBER"G21796-027"
MATERIAL"EMPTY"
WATTAGE"1/16W"
TOLERANCE"1%"
LOCATION"R3P54"
VALUE"3.32K"
CDS_LIB"mstr_discrete"
ROOM"CPU0"
SEC"1"
SEC_TYPE"0402";
"A"
$PN"1"14;
"B"
$PN"2"34;
%"P3V3_STBY"
"1","(-7650,1950)","0","mstr_symbols","I332";
;
VOLTAGE"3.3V"
CDS_LIB"mstr_symbols"
SIZE"1B"
BODY_TYPE"PLUMBING"
HDL_POWER"P3V3_STBY";
"G\NAC"14;
%"RES"
"2","(-7650,1325)","0","mstr_discrete","I333";
;
CDS_SEC"1"
CDS_LOCATION"R3P56"
PART_NUMBER"G21796-026"
MATERIAL"CHIP"
WATTAGE"1/16W"
VALUE"1.00K"
LOCATION"R3P56"
PACK_TYPE"0402"
TOLERANCE"1%"
CDS_LIB"mstr_discrete"
ROOM"CPU0"
SEC"1"
SEC_TYPE"0402";
"A"
$PN"1"34;
"B"
$PN"2"15;
%"GND"
"1","(-7650,1075)","0","mstr_symbols","I334";
;
VOLTAGE"0.0V"
CDS_LIB"mstr_symbols"
SIZE"1B"
BODY_TYPE"PLUMBING"
HDL_POWER"GND";
"A\NAC"15;
%"RES"
"2","(-6025,1725)","0","mstr_discrete","I336";
;
CDS_SEC"1"
CDS_LOCATION"R1C35"
PART_NUMBER"G21796-027"
MATERIAL"EMPTY"
WATTAGE"1/16W"
VALUE"3.32K"
TOLERANCE"1%"
PACK_TYPE"0402"
LOCATION"R1C35"
CDS_LIB"mstr_discrete"
SEC_TYPE"0402"
SEC"1"
ROOM"CPU1";
"A"
$PN"1"17;
"B"
$PN"2"35;
%"RES"
"2","(-6025,1350)","0","mstr_discrete","I337";
;
CDS_SEC"1"
CDS_LOCATION"R1C36"
PART_NUMBER"G21796-026"
PACK_TYPE"0402"
WATTAGE"1/16W"
MATERIAL"CHIP"
LOCATION"R1C36"
VALUE"1.00K"
TOLERANCE"1%"
CDS_LIB"mstr_discrete"
SEC_TYPE"0402"
SEC"1"
ROOM"CPU1";
"A"
$PN"1"35;
"B"
$PN"2"16;
%"GND"
"1","(-6025,1100)","0","mstr_symbols","I338";
;
VOLTAGE"0.0V"
CDS_LIB"mstr_symbols"
SIZE"1B"
BODY_TYPE"PLUMBING"
HDL_POWER"GND";
"A\NAC"16;
%"P3V3_STBY"
"1","(-6025,1975)","0","mstr_symbols","I339";
;
CDS_LIB"mstr_symbols"
VOLTAGE"3.3V"
SIZE"1B"
BODY_TYPE"PLUMBING"
HDL_POWER"P3V3_STBY";
"G\NAC"17;
%"SN74LVC2G07DCKR-GP"
"1","(-3225,4150)","0","w_hdl","I340";
;
CDS_SEC"1"
CDS_LOCATION"U8F3"
LOCATION"U8F3"
VALUE"SN74LVC2G07DCKR-GP"
PACK_TYPE"DISCRET-G4"
PART_NUMBER"73.02G07.02J"
SEC"1"
SEC_TYPE"DISCRET-G4"
CDS_LIB"w_hdl"
CDS_LMAN_SYM_OUTLINE"-175,150,175,-150";
"1Y"
$PN"6"28;
"VCC"
$PN"5"9;
"2Y"
$PN"4"29;
"2A"
$PN"3"26;
"GND"
$PN"2"18;
"1A"
$PN"1"24;
%"GND"
"1","(-3650,3950)","0","mstr_symbols","I341";
;
HDL_POWER"GND"
BODY_TYPE"PLUMBING"
SIZE"1B"
VOLTAGE"0.0V"
CDS_LIB"mstr_symbols";
"A\NAC"18;
%"SN74LVC2G07DCKR-GP"
"1","(-3225,2950)","0","w_hdl","I342";
;
CDS_SEC"1"
CDS_LOCATION"U8G1"
LOCATION"U8G1"
VALUE"SN74LVC2G07DCKR-GP"
PART_NUMBER"73.02G07.02J"
CDS_LMAN_SYM_OUTLINE"-175,150,175,-150"
CDS_LIB"w_hdl"
SEC_TYPE"DISCRET-G4"
SEC"1"
PACK_TYPE"DISCRET-G4";
"1Y"
$PN"6"28;
"VCC"
$PN"5"6;
"2Y"
$PN"4"29;
"2A"
$PN"3"31;
"GND"
$PN"2"19;
"1A"
$PN"1"30;
%"GND"
"1","(-3650,2750)","0","mstr_symbols","I343";
;
CDS_LIB"mstr_symbols"
VOLTAGE"0.0V"
SIZE"1B"
BODY_TYPE"PLUMBING"
HDL_POWER"GND";
"A\NAC"19;
END.
